# T6G (Grand Teton) — schematic netlist excerpt (pin names and nets, part order shuffled) for the footprints in the layout excerpt that follows; sources: Cadence DE-HDL packaged netlist, KiCad conversion of 04192023_DAF0TMB3IC0_F0TG_MB_C_brd_V02_OCP.brd

R6070  Q_RES  4.7K 5% EMPTY  pkg 0402LF  page 151 : A = P3V3_AUX ; B = JTAG_SCM_DBREQ_N
C2657  Q_CAP  22UF 4V 20% X6S  pkg C0402  page 70 : A = PVDD11_S3_P0 ; B = GND
C698  Q_CAP_DIFFBUS  DIFF BUS_0.22UF 6.3V 20% X6S  pkg C0201  page 67 : \1\ = P5E_CPU1_G1_TX_C_DN<5> ; \2\ = P5E_CPU1_G1_TX_DN<5>

(kicad_pcb
	(version 20260206)
	(generator "pcbnew")
	(generator_version "10.0")
	(general
		(thickness 1.6)
		(legacy_teardrops no)
	)
	(paper "A4")
	(title_block
		(title "04192023_DAF0TMB3IC0_F0TG_MB_C_brd_V02_OCP.brd")
		(comment 1 "Grand Teton / footprints 4012-4014 of 8354")
	)
	(layers
		(0 "F.Cu" signal "TOP")
		(4 "In1.Cu" signal "GND")
		(6 "In2.Cu" signal "IN1")
		(8 "In3.Cu" signal "GND1")
		(10 "In4.Cu" signal "IN2")
		(12 "In5.Cu" signal "GND2")
		(14 "In6.Cu" signal "IN3")
		(16 "In7.Cu" signal "GND3")
		(18 "In8.Cu" signal "VCC")
		(20 "In9.Cu" signal "VCC1")
		(22 "In10.Cu" signal "GND4")
		(24 "In11.Cu" signal "IN4")
		(26 "In12.Cu" signal "GND5")
		(28 "In13.Cu" signal "IN5")
		(30 "In14.Cu" signal "GND6")
		(32 "In15.Cu" signal "IN6")
		(34 "In16.Cu" signal "GND7")
		(2 "B.Cu" signal "BOTTOM")
		(9 "F.Adhes" user "F.Adhesive")
		(11 "B.Adhes" user "B.Adhesive")
		(13 "F.Paste" user "Package Geometry/Pastemask Top")
		(15 "B.Paste" user "Package Geometry/Pastemask Bottom")
		(5 "F.SilkS" user "Ref Des/Silkscreen Top")
		(7 "B.SilkS" user "Ref Des/Silkscreen Bottom")
		(1 "F.Mask" user "Board Geometry/Soldermask Top")
		(3 "B.Mask" user "Board Geometry/Soldermask Bottom")
		(17 "Dwgs.User" user "User.Drawings")
		(19 "Cmts.User" user "User.Comments")
		(21 "Eco1.User" user "User.Eco1")
		(23 "Eco2.User" user "User.Eco2")
		(25 "Edge.Cuts" user "Board Geometry/Outline")
		(27 "Margin" user)
		(31 "F.CrtYd" user "Package Geometry/Place Bound Top")
		(29 "B.CrtYd" user "Package Geometry/Place Bound Bottom")
		(35 "F.Fab" user "Ref Des/Assembly Top")
		(33 "B.Fab" user "Ref Des/Assembly Bottom")
	)
	(footprint ""
		(layer "F.Cu")
		(at 273.183604 -108.194856 -90)
		(property "Reference" "R6070"
			(at 0 0 270)
			(layer "F.SilkS")
			(hide yes)
			(effects
				(font
					(size 1.27 1.27)
				)
			)
		)
		(property "Value" ""
			(at 0 0 270)
			(layer "F.Fab")
			(effects
				(font
					(size 1.27 1.27)
				)
			)
		)
		(duplicate_pad_numbers_are_jumpers no)
		(fp_line
			(start -0.7874 0.4064)
			(end -0.7874 -0.4064)
			(stroke
				(width 0.1524)
				(type default)
			)
			(layer "F.SilkS")
		)
		(fp_line
			(start 0.7874 0.4064)
			(end -0.7874 0.4064)
			(stroke
				(width 0.1524)
				(type default)
			)
			(layer "F.SilkS")
		)
		(fp_line
			(start -0.7874 -0.4064)
			(end 0.7874 -0.4064)
			(stroke
				(width 0.1524)
				(type default)
			)
			(layer "F.SilkS")
		)
		(fp_line
			(start 0.7874 -0.4064)
			(end 0.7874 0.4064)
			(stroke
				(width 0.1524)
				(type default)
			)
			(layer "F.SilkS")
		)
		(fp_line
			(start -0.67945 0.3048)
			(end -0.67945 -0.305054)
			(stroke
				(width 0.1)
				(type default)
			)
			(layer "F.Fab")
		)
		(fp_line
			(start -0.12065 0.3048)
			(end -0.67945 0.3048)
			(stroke
				(width 0.1)
				(type default)
			)
			(layer "F.Fab")
		)
		(fp_line
			(start 0.120396 0.3048)
			(end 0.120396 0.2794)
			(stroke
				(width 0.1)
				(type default)
			)
			(layer "F.Fab")
		)
		(fp_line
			(start 0.67945 0.3048)
			(end 0.120396 0.3048)
			(stroke
				(width 0.1)
				(type default)
			)
			(layer "F.Fab")
		)
		(fp_line
			(start -0.12065 0.2794)
			(end -0.12065 0.3048)
			(stroke
				(width 0.1)
				(type default)
			)
			(layer "F.Fab")
		)
		(fp_line
			(start 0.120396 0.2794)
			(end -0.12065 0.2794)
			(stroke
				(width 0.1)
				(type default)
			)
			(layer "F.Fab")
		)
		(fp_line
			(start -0.12065 -0.2794)
			(end 0.12065 -0.2794)
			(stroke
				(width 0.1)
				(type default)
			)
			(layer "F.Fab")
		)
		(fp_line
			(start 0.12065 -0.2794)
			(end 0.12065 -0.3048)
			(stroke
				(width 0.1)
				(type default)
			)
			(layer "F.Fab")
		)
		(fp_line
			(start 0.12065 -0.3048)
			(end 0.67945 -0.3048)
			(stroke
				(width 0.1)
				(type default)
			)
			(layer "F.Fab")
		)
		(fp_line
			(start 0.67945 -0.3048)
			(end 0.67945 0.3048)
			(stroke
				(width 0.1)
				(type default)
			)
			(layer "F.Fab")
		)
		(fp_line
			(start -0.67945 -0.305054)
			(end -0.12065 -0.305054)
			(stroke
				(width 0.1)
				(type default)
			)
			(layer "F.Fab")
		)
		(fp_line
			(start -0.12065 -0.305054)
			(end -0.12065 -0.2794)
			(stroke
				(width 0.1)
				(type default)
			)
			(layer "F.Fab")
		)
		(pad "1" smd circle
			(at -0.40005 0 270)
			(size 0 0)
			(layers "F.Cu" "F.Mask" "F.Paste")
			(net "P3V3_AUX")
		)
		(pad "2" smd circle
			(at 0.40005 0 270)
			(size 0 0)
			(layers "F.Cu" "F.Mask" "F.Paste")
			(net "JTAG_SCM_DBREQ_N")
		)
	)
	(footprint ""
		(layer "F.Cu")
		(at 361.046014 -259.845048)
		(property "Reference" "C2657"
			(at 0 0 0)
			(layer "F.SilkS")
			(hide yes)
			(effects
				(font
					(size 1.27 1.27)
				)
			)
		)
		(property "Value" ""
			(at 0 0 0)
			(layer "F.Fab")
			(effects
				(font
					(size 1.27 1.27)
				)
			)
		)
		(duplicate_pad_numbers_are_jumpers no)
		(fp_line
			(start -0.7874 -0.4064)
			(end 0.7874 -0.4064)
			(stroke
				(width 0.1524)
				(type default)
			)
			(layer "F.SilkS")
		)
		(fp_line
			(start -0.7874 0.4064)
			(end -0.7874 -0.4064)
			(stroke
				(width 0.1524)
				(type default)
			)
			(layer "F.SilkS")
		)
		(fp_line
			(start 0.7874 -0.4064)
			(end 0.7874 0.4064)
			(stroke
				(width 0.1524)
				(type default)
			)
			(layer "F.SilkS")
		)
		(fp_line
			(start 0.7874 0.4064)
			(end -0.7874 0.4064)
			(stroke
				(width 0.1524)
				(type default)
			)
			(layer "F.SilkS")
		)
		(fp_line
			(start -0.67945 -0.305054)
			(end -0.12065 -0.305054)
			(stroke
				(width 0.1)
				(type default)
			)
			(layer "F.Fab")
		)
		(fp_line
			(start -0.67945 0.3048)
			(end -0.67945 -0.305054)
			(stroke
				(width 0.1)
				(type default)
			)
			(layer "F.Fab")
		)
		(fp_line
			(start -0.12065 -0.305054)
			(end -0.12065 -0.2794)
			(stroke
				(width 0.1)
				(type default)
			)
			(layer "F.Fab")
		)
		(fp_line
			(start -0.12065 -0.2794)
			(end 0.12065 -0.2794)
			(stroke
				(width 0.1)
				(type default)
			)
			(layer "F.Fab")
		)
		(fp_line
			(start -0.12065 0.2794)
			(end -0.12065 0.3048)
			(stroke
				(width 0.1)
				(type default)
			)
			(layer "F.Fab")
		)
		(fp_line
			(start -0.12065 0.3048)
			(end -0.67945 0.3048)
			(stroke
				(width 0.1)
				(type default)
			)
			(layer "F.Fab")
		)
		(fp_line
			(start 0.120396 0.2794)
			(end -0.12065 0.2794)
			(stroke
				(width 0.1)
				(type default)
			)
			(layer "F.Fab")
		)
		(fp_line
			(start 0.120396 0.3048)
			(end 0.120396 0.2794)
			(stroke
				(width 0.1)
				(type default)
			)
			(layer "F.Fab")
		)
		(fp_line
			(start 0.12065 -0.3048)
			(end 0.67945 -0.3048)
			(stroke
				(width 0.1)
				(type default)
			)
			(layer "F.Fab")
		)
		(fp_line
			(start 0.12065 -0.2794)
			(end 0.12065 -0.3048)
			(stroke
				(width 0.1)
				(type default)
			)
			(layer "F.Fab")
		)
		(fp_line
			(start 0.67945 -0.3048)
			(end 0.67945 0.3048)
			(stroke
				(width 0.1)
				(type default)
			)
			(layer "F.Fab")
		)
		(fp_line
			(start 0.67945 0.3048)
			(end 0.120396 0.3048)
			(stroke
				(width 0.1)
				(type default)
			)
			(layer "F.Fab")
		)
		(pad "1" smd circle
			(at -0.40005 0)
			(size 0 0)
			(layers "F.Cu" "F.Mask" "F.Paste")
			(net "PVDD11_S3_P0")
		)
		(pad "2" smd circle
			(at 0.40005 0)
			(size 0 0)
			(layers "F.Cu" "F.Mask" "F.Paste")
			(net "GND")
		)
	)
	(footprint ""
		(layer "F.Cu")
		(at 43.754294 -16.099536 90)
		(property "Reference" "C698"
			(at 0 0 90)
			(layer "F.SilkS")
			(hide yes)
			(effects
				(font
					(size 1.27 1.27)
				)
			)
		)
		(property "Value" ""
			(at 0 0 90)
			(layer "F.Fab")
			(effects
				(font
					(size 1.27 1.27)
				)
			)
		)
		(duplicate_pad_numbers_are_jumpers no)
		(fp_line
			(start 0.299974 -0.150114)
			(end 0.299974 0.150114)
			(stroke
				(width 0.1)
				(type default)
			)
			(layer "F.Fab")
		)
		(fp_line
			(start -0.299974 -0.150114)
			(end 0.299974 -0.150114)
			(stroke
				(width 0.1)
				(type default)
			)
			(layer "F.Fab")
		)
		(fp_line
			(start 0.299974 0.150114)
			(end -0.299974 0.150114)
			(stroke
				(width 0.1)
				(type default)
			)
			(layer "F.Fab")
		)
		(fp_line
			(start -0.299974 0.150114)
			(end -0.299974 -0.150114)
			(stroke
				(width 0.1)
				(type default)
			)
			(layer "F.Fab")
		)
		(pad "1" smd rect
			(at -0.2667 0 90)
			(size 0.3048 0.381)
			(layers "F.Cu" "F.Mask" "F.Paste")
			(net "P5E_CPU1_G1_TX_C_DN<5>")
		)
		(pad "2" smd rect
			(at 0.2667 0 90)
			(size 0.3048 0.381)
			(layers "F.Cu" "F.Mask" "F.Paste")
			(net "P5E_CPU1_G1_TX_DN<5>")
		)
	)
)
